# BASEBOARD_FAB2 (Tioga Pass) — schematic netlist excerpt (pin names and nets, part order shuffled) for the footprints in the layout excerpt that follows; sources: Cadence DE-HDL packaged netlist, KiCad conversion of Wiwynn_Tioga_Pass_MB.brd

C6U14  CAP  10UF 4V 20% X6S  pkg 0603LF  page 229 : A = PVDDQ_GHJ ; B = GND
C5P41  CAP  100UF 4V 20% X5R  pkg 0805  page 217 : A = PVDDQ_ABC ; B = GND
R25W82  RES  33.2 1% CHIP  pkg 0402  page 146 : A = SPI_BMC_BT_DO ; B = SPI_BMC_BT_DO_R

(kicad_pcb
	(version 20260206)
	(generator "pcbnew")
	(generator_version "10.0")
	(general
		(thickness 1.6)
		(legacy_teardrops no)
	)
	(paper "A4")
	(title_block
		(title "Wiwynn_Tioga_Pass_MB.brd")
		(comment 1 "Tioga Pass / footprints 2446-2448 of 4770")
	)
	(layers
		(0 "F.Cu" signal "TOP")
		(4 "In1.Cu" signal "L2GND")
		(6 "In2.Cu" signal "L3")
		(8 "In3.Cu" signal "L4GND")
		(10 "In4.Cu" signal "L5")
		(12 "In5.Cu" signal "L6GND")
		(14 "In6.Cu" signal "L7VCC")
		(16 "In7.Cu" signal "L8VCC")
		(18 "In8.Cu" signal "L9GND")
		(20 "In9.Cu" signal "L10")
		(22 "In10.Cu" signal "L11GND")
		(24 "In11.Cu" signal "L12")
		(26 "In12.Cu" signal "L13GND")
		(2 "B.Cu" signal "BOTTOM")
		(9 "F.Adhes" user "F.Adhesive")
		(11 "B.Adhes" user "B.Adhesive")
		(13 "F.Paste" user "Package Geometry/Pastemask Top")
		(15 "B.Paste" user "Package Geometry/Pastemask Bottom")
		(5 "F.SilkS" user "Ref Des/Silkscreen Top")
		(7 "B.SilkS" user "Ref Des/Silkscreen Bottom")
		(1 "F.Mask" user "Board Geometry/Soldermask Top")
		(3 "B.Mask" user "Board Geometry/Soldermask Bottom")
		(17 "Dwgs.User" user "User.Drawings")
		(19 "Cmts.User" user "User.Comments")
		(21 "Eco1.User" user "User.Eco1")
		(23 "Eco2.User" user "User.Eco2")
		(25 "Edge.Cuts" user "Board Geometry/Outline")
		(27 "Margin" user)
		(31 "F.CrtYd" user "Package Geometry/Place Bound Top")
		(29 "B.CrtYd" user "Package Geometry/Place Bound Bottom")
		(35 "F.Fab" user "Ref Des/Assembly Top")
		(33 "B.Fab" user "Ref Des/Assembly Bottom")
	)
	(footprint ""
		(layer "B.Cu")
		(at 421.812466 -44.647612 -90)
		(property "Reference" "R25W82"
			(at 0.8382 -0.67818 270)
			(unlocked yes)
			(layer "B.SilkS")
			(effects
				(font
					(size 0.4064 0.254)
					(thickness 0.1524)
				)
				(justify left mirror)
			)
		)
		(property "Value" ""
			(at 0 0 90)
			(layer "B.Fab")
			(effects
				(font
					(size 1.27 1.27)
				)
				(justify mirror)
			)
		)
		(duplicate_pad_numbers_are_jumpers no)
		(fp_poly
			(pts
				(xy 0.2794 -0.1016) (xy -0.2794 -0.1016) (xy -0.2794 0.9906) (xy 0.2794 0.9906)
			)
			(stroke
				(width 0)
				(type default)
			)
			(fill no)
			(layer "B.CrtYd")
		)
		(fp_line
			(start -0.2794 0.9906)
			(end -0.2794 -0.1016)
			(stroke
				(width 0.1)
				(type default)
			)
			(layer "B.Fab")
		)
		(fp_line
			(start 0.2794 0.9906)
			(end -0.2794 0.9906)
			(stroke
				(width 0.1)
				(type default)
			)
			(layer "B.Fab")
		)
		(fp_line
			(start -0.2794 -0.1016)
			(end 0.2794 -0.1016)
			(stroke
				(width 0.1)
				(type default)
			)
			(layer "B.Fab")
		)
		(fp_line
			(start 0.2794 -0.1016)
			(end 0.2794 0.9906)
			(stroke
				(width 0.1)
				(type default)
			)
			(layer "B.Fab")
		)
		(pad "1" smd rect
			(at 0 0 90)
			(size 0.508 0.508)
			(layers "B.Cu" "B.Mask" "B.Paste")
			(net "SPI_BMC_BT_DO")
		)
		(pad "2" smd rect
			(at 0 0.889 90)
			(size 0.508 0.508)
			(layers "B.Cu" "B.Mask" "B.Paste")
			(net "SPI_BMC_BT_DO_R")
		)
		(zone
			(layer "B.Cu")
			(hatch none 0.5)
			(connect_pads
				(clearance 0)
			)
			(min_thickness 0.25)
			(keepout
				(tracks not_allowed)
				(vias allowed)
				(pads allowed)
				(copperpour not_allowed)
				(footprints allowed)
			)
			(placement
				(enabled no)
				(sheetname "")
			)
			(fill
				(thermal_gap 0.5)
				(thermal_bridge_width 0.5)
				(island_removal_mode 0)
			)
			(polygon
				(pts
					(xy 421.177466 -44.393612) (xy 421.177466 -44.901612) (xy 421.558466 -44.901612) (xy 421.558466 -44.393612)
				)
			)
		)
		(zone
			(layer "B.Cu")
			(hatch none 0.5)
			(connect_pads
				(clearance 0)
			)
			(min_thickness 0.25)
			(keepout
				(tracks allowed)
				(vias not_allowed)
				(pads allowed)
				(copperpour not_allowed)
				(footprints allowed)
			)
			(placement
				(enabled no)
				(sheetname "")
			)
			(fill
				(thermal_gap 0.5)
				(thermal_bridge_width 0.5)
				(island_removal_mode 0)
			)
			(polygon
				(pts
					(xy 421.558466 -44.393612) (xy 421.558466 -44.901612) (xy 421.177466 -44.901612) (xy 421.177466 -44.393612)
				)
			)
		)
	)
	(footprint ""
		(layer "B.Cu")
		(at 169.037 -3.4544 90)
		(property "Reference" "C6U14"
			(at 0 0 90)
			(layer "B.SilkS")
			(hide yes)
			(effects
				(font
					(size 1.27 1.27)
				)
				(justify mirror)
			)
		)
		(property "Value" ""
			(at 0 0 90)
			(layer "B.Fab")
			(effects
				(font
					(size 1.27 1.27)
				)
				(justify mirror)
			)
		)
		(duplicate_pad_numbers_are_jumpers no)
		(fp_rect
			(start -0.4953 1.6002)
			(end 0.4953 -0.2032)
			(stroke
				(width 0)
				(type default)
			)
			(fill no)
			(layer "B.CrtYd")
		)
		(fp_line
			(start 0.4953 -0.2032)
			(end -0.4953 -0.2032)
			(stroke
				(width 0.1)
				(type default)
			)
			(layer "B.Fab")
		)
		(fp_line
			(start -0.4953 -0.2032)
			(end -0.4953 1.6002)
			(stroke
				(width 0.1)
				(type default)
			)
			(layer "B.Fab")
		)
		(fp_line
			(start 0.4953 1.6002)
			(end 0.4953 -0.2032)
			(stroke
				(width 0.1)
				(type default)
			)
			(layer "B.Fab")
		)
		(fp_line
			(start -0.4953 1.6002)
			(end 0.4953 1.6002)
			(stroke
				(width 0.1)
				(type default)
			)
			(layer "B.Fab")
		)
		(pad "1" smd rect
			(at 0 0 270)
			(size 0.762 0.889)
			(layers "B.Cu" "B.Mask" "B.Paste")
			(net "PVDDQ_GHJ")
		)
		(pad "2" smd rect
			(at 0 1.397 270)
			(size 0.762 0.889)
			(layers "B.Cu" "B.Mask" "B.Paste")
			(net "GND")
		)
		(zone
			(layer "B.Cu")
			(hatch none 0.5)
			(connect_pads
				(clearance 0)
			)
			(min_thickness 0.25)
			(keepout
				(tracks not_allowed)
				(vias allowed)
				(pads allowed)
				(copperpour not_allowed)
				(footprints allowed)
			)
			(placement
				(enabled no)
				(sheetname "")
			)
			(fill
				(thermal_gap 0.5)
				(thermal_bridge_width 0.5)
				(island_removal_mode 0)
			)
			(polygon
				(pts
					(xy 169.9895 -3.0734) (xy 169.9895 -3.8354) (xy 169.4815 -3.8354) (xy 169.4815 -3.0734)
				)
			)
		)
	)
	(footprint ""
		(layer "B.Cu")
		(at 273.433286 -68.17614 180)
		(property "Reference" "C5P41"
			(at 0 0 0)
			(layer "B.SilkS")
			(hide yes)
			(effects
				(font
					(size 1.27 1.27)
				)
				(justify mirror)
			)
		)
		(property "Value" ""
			(at 0 0 0)
			(layer "B.Fab")
			(effects
				(font
					(size 1.27 1.27)
				)
				(justify mirror)
			)
		)
		(duplicate_pad_numbers_are_jumpers no)
		(fp_poly
			(pts
				(xy 0.7239 -0.2159) (xy -0.7239 -0.2159) (xy -0.7239 1.9939) (xy 0.7239 1.9939)
			)
			(stroke
				(width 0)
				(type default)
			)
			(fill no)
			(layer "B.CrtYd")
		)
		(fp_line
			(start 0.7239 1.9939)
			(end -0.7239 1.9939)
			(stroke
				(width 0.1)
				(type default)
			)
			(layer "B.Fab")
		)
		(fp_line
			(start 0.7239 -0.2159)
			(end 0.7239 1.9939)
			(stroke
				(width 0.1)
				(type default)
			)
			(layer "B.Fab")
		)
		(fp_line
			(start -0.7239 1.9939)
			(end -0.7239 -0.2159)
			(stroke
				(width 0.1)
				(type default)
			)
			(layer "B.Fab")
		)
		(fp_line
			(start -0.7239 -0.2159)
			(end 0.7239 -0.2159)
			(stroke
				(width 0.1)
				(type default)
			)
			(layer "B.Fab")
		)
		(pad "1" smd rect
			(at 0 0)
			(size 1.27 1.016)
			(layers "B.Cu" "B.Mask" "B.Paste")
			(net "PVDDQ_ABC")
		)
		(pad "2" smd rect
			(at 0 1.778)
			(size 1.27 1.016)
			(layers "B.Cu" "B.Mask" "B.Paste")
			(net "GND")
		)
		(zone
			(layer "B.Cu")
			(hatch none 0.5)
			(connect_pads
				(clearance 0)
			)
			(min_thickness 0.25)
			(keepout
				(tracks not_allowed)
				(vias allowed)
				(pads allowed)
				(copperpour not_allowed)
				(footprints allowed)
			)
			(placement
				(enabled no)
				(sheetname "")
			)
			(fill
				(thermal_gap 0.5)
				(thermal_bridge_width 0.5)
				(island_removal_mode 0)
			)
			(polygon
				(pts
					(xy 272.798286 -68.68414) (xy 274.068286 -68.68414) (xy 274.068286 -69.44614) (xy 272.798286 -69.44614)
				)
			)
		)
	)
)
